(kicad_pcb
	(version 20241229)
	(generator "pcbnew")
	(generator_version "9.0")
	(general
		(thickness 1.63)
		(legacy_teardrops no)
	)
	(paper "A4")
	(title_block
		(title "CM4 Baseboard")
		(date "2026-01-05")
		(rev "1.1.1")
		(company "Antmicro Ltd")
		(comment 1 "www.antmicro.com")
		(comment 9 "footprints 361-364 of 506")
	)
	(layers
		(0 "F.Cu" signal)
		(4 "In1.Cu" power)
		(6 "In2.Cu" power)
		(8 "In3.Cu" signal)
		(10 "In4.Cu" signal)
		(2 "B.Cu" signal)
		(9 "F.Adhes" user "F.Adhesive")
		(11 "B.Adhes" user "B.Adhesive")
		(13 "F.Paste" user)
		(15 "B.Paste" user)
		(5 "F.SilkS" user "F.Silkscreen")
		(7 "B.SilkS" user "B.Silkscreen")
		(1 "F.Mask" user)
		(3 "B.Mask" user)
		(17 "Dwgs.User" user "User.Drawings")
		(19 "Cmts.User" user "User.Comments")
		(21 "Eco1.User" user "User.Eco1")
		(23 "Eco2.User" user "User.Eco2")
		(25 "Edge.Cuts" user)
		(27 "Margin" user)
		(31 "F.CrtYd" user "F.Courtyard")
		(29 "B.CrtYd" user "B.Courtyard")
		(35 "F.Fab" user)
		(33 "B.Fab" user)
	)
	(footprint "antmicro-footprints:C_2220_5650Metric"
		(layer "B.Cu")
		(at 55.117962 145.6465 90)
		(descr "Capacitor SMD 2220")
		(tags "capacitor SMD 2220")
		(property "Reference" "C405"
			(at -4.405 -1.29 180)
			(layer "B.SilkS")
			(effects
				(font
					(size 0.7 0.7)
					(thickness 0.15)
				)
				(justify right bottom mirror)
			)
		)
		(property "Value" "C_22u_100V_2220"
			(at 0 -3.9 90)
			(layer "B.Fab")
			(effects
				(font
					(size 0.7 0.7)
					(thickness 0.15)
				)
				(justify right bottom mirror)
			)
		)
		(property "Datasheet" "https://product.tdk.com/en/search/capacitor/ceramic/mlcc/info?part_no=C5750X7S2A226M280KB"
			(at 0 0 90)
			(layer "B.Fab")
			(hide yes)
			(effects
				(font
					(size 1.27 1.27)
					(thickness 0.15)
				)
			)
		)
		(property "Manufacturer" "TDK"
			(at 0 0 90)
			(unlocked yes)
			(layer "B.Fab")
			(hide yes)
			(effects
				(font
					(size 1 1)
					(thickness 0.15)
				)
				(justify mirror)
			)
		)
		(property "MPN" "C5750X7S2A226M280KB"
			(at 0 0 90)
			(unlocked yes)
			(layer "B.Fab")
			(hide yes)
			(effects
				(font
					(size 1 1)
					(thickness 0.15)
				)
				(justify mirror)
			)
		)
		(property "Val" "22u"
			(at 0 0 90)
			(unlocked yes)
			(layer "B.Fab")
			(hide yes)
			(effects
				(font
					(size 1 1)
					(thickness 0.15)
				)
				(justify mirror)
			)
		)
		(property "License" "Apache-2.0"
			(at 0 0 90)
			(unlocked yes)
			(layer "B.Fab")
			(hide yes)
			(effects
				(font
					(size 1 1)
					(thickness 0.15)
				)
				(justify mirror)
			)
		)
		(property "Author" "Antmicro"
			(at 0 0 90)
			(unlocked yes)
			(layer "B.Fab")
			(hide yes)
			(effects
				(font
					(size 1 1)
					(thickness 0.15)
				)
				(justify mirror)
			)
		)
		(property "Voltage" "100V"
			(at 0 0 90)
			(unlocked yes)
			(layer "B.Fab")
			(hide yes)
			(effects
				(font
					(size 1 1)
					(thickness 0.15)
				)
				(justify mirror)
			)
		)
		(property "Dielectric" "X7S"
			(at 0 0 90)
			(unlocked yes)
			(layer "B.Fab")
			(hide yes)
			(effects
				(font
					(size 1 1)
					(thickness 0.15)
				)
				(justify mirror)
			)
		)
		(property "Public" "False"
			(at 0 0 90)
			(unlocked yes)
			(layer "B.Fab")
			(hide yes)
			(effects
				(font
					(size 1 1)
					(thickness 0.15)
				)
				(justify mirror)
			)
		)
		(sheetname "/Ethernet/")
		(sheetfile "ethernet.kicad_sch")
		(attr smd)
		(fp_line
			(start -1.415 -2.61)
			(end 1.415 -2.61)
			(stroke
				(width 0.15)
				(type solid)
			)
			(layer "B.SilkS")
		)
		(fp_line
			(start -1.415 2.61)
			(end 1.415 2.61)
			(stroke
				(width 0.15)
				(type solid)
			)
			(layer "B.SilkS")
		)
		(fp_rect
			(start -3.7 2.95)
			(end 3.7 -2.95)
			(stroke
				(width 0.05)
				(type solid)
			)
			(fill no)
			(layer "B.CrtYd")
		)
		(fp_rect
			(start -2.85 2.5)
			(end 2.85 -2.5)
			(stroke
				(width 0.15)
				(type solid)
			)
			(fill no)
			(layer "B.Fab")
		)
		(fp_text user "Author: Antmicro"
			(at -3.7 -7.9 270)
			(layer "B.Fab")
			(effects
				(font
					(size 0.7 0.7)
					(thickness 0.15)
				)
				(justify left bottom mirror)
			)
		)
		(fp_text user "${REFERENCE}"
			(at -3.7 -5.9 270)
			(layer "B.Fab")
			(effects
				(font
					(size 0.7 0.7)
					(thickness 0.15)
				)
				(justify left bottom mirror)
			)
		)
		(fp_text user "License: Apache-2.0"
			(at -3.7 -6.9 270)
			(layer "B.Fab")
			(effects
				(font
					(size 0.7 0.7)
					(thickness 0.15)
				)
				(justify left bottom mirror)
			)
		)
		(pad "1" smd roundrect
			(at -2.55 0 90)
			(size 1.8 5.4)
			(layers "B.Cu" "B.Mask" "B.Paste")
			(roundrect_rratio 0.138889)
			(net 1 "GNDD")
			(pintype "passive")
		)
		(pad "2" smd roundrect
			(at 2.55 0 90)
			(size 1.8 5.4)
			(layers "B.Cu" "B.Mask" "B.Paste")
			(roundrect_rratio 0.138889)
			(net 33 "/Ethernet/VDD")
			(pintype "passive")
		)
	)
	(footprint "antmicro-footprints:SOIC-4_4.55x2.6mm_P1.27mm"
		(layer "B.Cu")
		(at 56.792962 135.4665 180)
		(descr "ACPL-217-500E")
		(tags "Integrated Circuit")
		(property "Reference" "U402"
			(at -1.395 1.87 0)
			(layer "B.SilkS")
			(effects
				(font
					(size 0.7 0.7)
					(thickness 0.15)
				)
				(justify left bottom mirror)
			)
		)
		(property "Value" "ACPL-217-500E"
			(at -4.25 -2.75 0)
			(layer "B.Fab")
			(effects
				(font
					(size 0.7 0.7)
					(thickness 0.15)
				)
				(justify left bottom mirror)
			)
		)
		(property "Datasheet" "https://docs.broadcom.com/doc/AV02-0470EN"
			(at 0 0 180)
			(layer "B.Fab")
			(hide yes)
			(effects
				(font
					(size 1.27 1.27)
					(thickness 0.15)
				)
			)
		)
		(property "Description" "Broadcom ACPL-217-500E DC Input Transistor Output Optocoupler, Surface Mount, 4-Pin SO"
			(at 113.585924 270.933 0)
			(layer "B.Fab")
			(hide yes)
			(effects
				(font
					(size 1.27 1.27)
					(thickness 0.15)
				)
			)
		)
		(property "Manufacturer" "Broadcom"
			(at 0 0 180)
			(unlocked yes)
			(layer "B.Fab")
			(hide yes)
			(effects
				(font
					(size 1 1)
					(thickness 0.15)
				)
				(justify mirror)
			)
		)
		(property "MPN" "ACPL-217-500E"
			(at 0 0 180)
			(unlocked yes)
			(layer "B.Fab")
			(hide yes)
			(effects
				(font
					(size 1 1)
					(thickness 0.15)
				)
				(justify mirror)
			)
		)
		(property "Author" "Antmicro"
			(at 0 0 180)
			(unlocked yes)
			(layer "B.Fab")
			(hide yes)
			(effects
				(font
					(size 1 1)
					(thickness 0.15)
				)
				(justify mirror)
			)
		)
		(property "License" "Apache-2.0"
			(at 0 0 180)
			(unlocked yes)
			(layer "B.Fab")
			(hide yes)
			(effects
				(font
					(size 1 1)
					(thickness 0.15)
				)
				(justify mirror)
			)
		)
		(sheetname "/Ethernet/")
		(sheetfile "ethernet.kicad_sch")
		(attr smd)
		(fp_line
			(start 2.3 1.1)
			(end 2.3 1.4)
			(stroke
				(width 0.12)
				(type solid)
			)
			(layer "B.SilkS")
		)
		(fp_line
			(start 2.3 -1.1)
			(end 2.3 -1.4)
			(stroke
				(width 0.12)
				(type solid)
			)
			(layer "B.SilkS")
		)
		(fp_line
			(start 2.3 -1.4)
			(end 1.8 -1.4)
			(stroke
				(width 0.12)
				(type solid)
			)
			(layer "B.SilkS")
		)
		(fp_line
			(start 1.8 1.4)
			(end 2.3 1.4)
			(stroke
				(width 0.12)
				(type solid)
			)
			(layer "B.SilkS")
		)
		(fp_line
			(start -1.8 -1.4)
			(end -2.3 -1.4)
			(stroke
				(width 0.12)
				(type solid)
			)
			(layer "B.SilkS")
		)
		(fp_line
			(start -2.3 1.4)
			(end -1.8 1.4)
			(stroke
				(width 0.12)
				(type solid)
			)
			(layer "B.SilkS")
		)
		(fp_line
			(start -2.3 -1.1)
			(end -2.3 -1.4)
			(stroke
				(width 0.12)
				(type solid)
			)
			(layer "B.SilkS")
		)
		(fp_line
			(start 4.29 1.7)
			(end 4.29 -1.69)
			(stroke
				(width 0.05)
				(type solid)
			)
			(layer "B.CrtYd")
		)
		(fp_line
			(start 4.29 -1.69)
			(end -4.3 -1.69)
			(stroke
				(width 0.05)
				(type solid)
			)
			(layer "B.CrtYd")
		)
		(fp_line
			(start -4.3 1.7)
			(end 4.29 1.7)
			(stroke
				(width 0.05)
				(type solid)
			)
			(layer "B.CrtYd")
		)
		(fp_line
			(start -4.3 -1.69)
			(end -4.3 1.7)
			(stroke
				(width 0.05)
				(type solid)
			)
			(layer "B.CrtYd")
		)
		(fp_line
			(start 2.2 1.301)
			(end 2.2 -1.3)
			(stroke
				(width 0.15)
				(type solid)
			)
			(layer "B.Fab")
		)
		(fp_line
			(start 2.2 -1.3)
			(end -2.201 -1.3)
			(stroke
				(width 0.15)
				(type solid)
			)
			(layer "B.Fab")
		)
		(fp_line
			(start -2.201 1.301)
			(end 2.2 1.301)
			(stroke
				(width 0.15)
				(type solid)
			)
			(layer "B.Fab")
		)
		(fp_line
			(start -2.201 0.03)
			(end -0.931 1.301)
			(stroke
				(width 0.15)
				(type solid)
			)
			(layer "B.Fab")
		)
		(fp_line
			(start -2.201 -1.3)
			(end -2.201 1.301)
			(stroke
				(width 0.15)
				(type solid)
			)
			(layer "B.Fab")
		)
		(fp_text user "."
			(at -2.7 1.6 0)
			(layer "B.SilkS")
			(effects
				(font
					(size 1 1)
					(thickness 0.15)
				)
				(justify mirror)
			)
		)
		(fp_text user "License: Apache-2.0"
			(at -4.25 -7 0)
			(layer "B.Fab")
			(effects
				(font
					(size 0.7 0.7)
					(thickness 0.15)
				)
				(justify left bottom mirror)
			)
		)
		(fp_text user "Author: Antmicro"
			(at -4.3 -5.5 0)
			(layer "B.Fab")
			(effects
				(font
					(size 0.7 0.7)
					(thickness 0.15)
				)
				(justify left bottom mirror)
			)
		)
		(fp_text user "${REFERENCE}"
			(at -4.3 -4.25 0)
			(layer "B.Fab")
			(effects
				(font
					(size 0.7 0.7)
					(thickness 0.15)
				)
				(justify left bottom mirror)
			)
		)
		(pad "1" smd roundrect
			(at -3.125 0.635 90)
			(size 0.65 1.85)
			(layers "B.Cu" "B.Mask" "B.Paste")
			(roundrect_rratio 0.15)
			(net 386 "/Compute module/~{POE EN}")
			(pintype "passive")
		)
		(pad "2" smd roundrect
			(at -3.125 -0.634 90)
			(size 0.65 1.85)
			(layers "B.Cu" "B.Mask" "B.Paste")
			(roundrect_rratio 0.15)
			(net 367 "Net-(R421-Pad1)")
			(pintype "passive")
		)
		(pad "3" smd roundrect
			(at 3.124 -0.634 90)
			(size 0.65 1.85)
			(layers "B.Cu" "B.Mask" "B.Paste")
			(roundrect_rratio 0.15)
			(net 366 "Net-(R418-Pad2)")
			(pintype "passive")
		)
		(pad "4" smd roundrect
			(at 3.124 0.635 90)
			(size 0.65 1.85)
			(layers "B.Cu" "B.Mask" "B.Paste")
			(roundrect_rratio 0.15)
			(net 339 "/Ethernet/POE_ACTIVE")
			(pintype "passive")
		)
	)
	(footprint "antmicro-footprints:C_0402_1005Metric"
		(layer "B.Cu")
		(at 43.797962 158.6365)
		(descr "Capacitor SMD 0402")
		(tags "capacitor SMD 0402")
		(property "Reference" "C301"
			(at -1.13 1.34 0)
			(layer "B.SilkS")
			(effects
				(font
					(size 0.7 0.7)
					(thickness 0.15)
				)
				(justify right bottom mirror)
			)
		)
		(property "Value" "C_1u_25V_0402"
			(at -1.022927 -2.155213 0)
			(layer "B.Fab")
			(effects
				(font
					(size 0.7 0.7)
					(thickness 0.15)
				)
				(justify right bottom mirror)
			)
		)
		(property "Datasheet" "https://www.murata.com/products/productdetail?partno=GRM155R61E105KE11%23"
			(at 0 0 0)
			(layer "B.Fab")
			(hide yes)
			(effects
				(font
					(size 1.27 1.27)
					(thickness 0.15)
				)
			)
		)
		(property "MPN" "GRM155R61E105KE11J"
			(at 0 0 0)
			(unlocked yes)
			(layer "B.Fab")
			(hide yes)
			(effects
				(font
					(size 1 1)
					(thickness 0.15)
				)
				(justify mirror)
			)
		)
		(property "Manufacturer" "Murata"
			(at 0 0 0)
			(unlocked yes)
			(layer "B.Fab")
			(hide yes)
			(effects
				(font
					(size 1 1)
					(thickness 0.15)
				)
				(justify mirror)
			)
		)
		(property "License" "Apache-2.0"
			(at 0 0 0)
			(unlocked yes)
			(layer "B.Fab")
			(hide yes)
			(effects
				(font
					(size 1 1)
					(thickness 0.15)
				)
				(justify mirror)
			)
		)
		(property "Author" "Antmicro"
			(at 0 0 0)
			(unlocked yes)
			(layer "B.Fab")
			(hide yes)
			(effects
				(font
					(size 1 1)
					(thickness 0.15)
				)
				(justify mirror)
			)
		)
		(property "Val" "1u"
			(at 0 0 0)
			(unlocked yes)
			(layer "B.Fab")
			(hide yes)
			(effects
				(font
					(size 1 1)
					(thickness 0.15)
				)
				(justify mirror)
			)
		)
		(property "Voltage" "25V"
			(at 0 0 0)
			(unlocked yes)
			(layer "B.Fab")
			(hide yes)
			(effects
				(font
					(size 1 1)
					(thickness 0.15)
				)
				(justify mirror)
			)
		)
		(property "Dielectric" "X5R"
			(at 0 0 0)
			(unlocked yes)
			(layer "B.Fab")
			(hide yes)
			(effects
				(font
					(size 1 1)
					(thickness 0.15)
				)
				(justify mirror)
			)
		)
		(sheetname "/Supply/")
		(sheetfile "supply.kicad_sch")
		(attr smd)
		(fp_rect
			(start -0.925 0.47)
			(end 0.925 -0.47)
			(stroke
				(width 0.05)
				(type default)
			)
			(fill no)
			(layer "B.CrtYd")
		)
		(fp_line
			(start -0.494 -0.248)
			(end -0.494 0.25)
			(stroke
				(width 0.15)
				(type solid)
			)
			(layer "B.Fab")
		)
		(fp_line
			(start -0.494 0.25)
			(end 0.504 0.25)
			(stroke
				(width 0.15)
				(type solid)
			)
			(layer "B.Fab")
		)
		(fp_line
			(start 0.504 -0.248)
			(end -0.494 -0.248)
			(stroke
				(width 0.15)
				(type solid)
			)
			(layer "B.Fab")
		)
		(fp_line
			(start 0.504 0.25)
			(end 0.504 -0.248)
			(stroke
				(width 0.15)
				(type solid)
			)
			(layer "B.Fab")
		)
		(fp_text user "${REFERENCE}"
			(at -0.939 -4.599 180)
			(layer "B.Fab")
			(effects
				(font
					(size 0.7 0.7)
					(thickness 0.15)
				)
				(justify left bottom mirror)
			)
		)
		(fp_text user "Author: Antmicro"
			(at -0.939 -3.399 180)
			(layer "B.Fab")
			(effects
				(font
					(size 0.7 0.7)
					(thickness 0.15)
				)
				(justify left bottom mirror)
			)
		)
		(fp_text user "License: Apache-2.0"
			(at -0.939 -5.799 180)
			(layer "B.Fab")
			(effects
				(font
					(size 0.7 0.7)
					(thickness 0.15)
				)
				(justify left bottom mirror)
			)
		)
		(pad "1" smd roundrect
			(at -0.48 0)
			(size 0.59 0.64)
			(layers "B.Cu" "B.Mask" "B.Paste")
			(roundrect_rratio 0.25)
			(net 17 "Net-(Q307-G)")
			(pintype "passive")
		)
		(pad "2" smd roundrect
			(at 0.48 0)
			(size 0.59 0.64)
			(layers "B.Cu" "B.Mask" "B.Paste")
			(roundrect_rratio 0.25)
			(net 21 "/Supply/VCC_IN")
			(pintype "passive")
		)
	)
	(footprint "antmicro-footprints:R_0402_1005Metric"
		(layer "B.Cu")
		(at 78.767962 152.2165 180)
		(descr "Resistor SMD 0402")
		(tags "resistor SMD 0402")
		(property "Reference" "R243"
			(at -5.06 -1.86 0)
			(layer "B.SilkS")
			(effects
				(font
					(size 0.7 0.7)
					(thickness 0.15)
				)
				(justify left bottom mirror)
			)
		)
		(property "Value" "R_2k2_0402"
			(at -1.011843 -1.772047 0)
			(layer "B.Fab")
			(effects
				(font
					(size 0.7 0.7)
					(thickness 0.15)
				)
				(justify left bottom mirror)
			)
		)
		(property "Datasheet" "https://www.bourns.com/docs/product-datasheets/cr.pdf"
			(at 0 0 180)
			(layer "B.Fab")
			(hide yes)
			(effects
				(font
					(size 1.27 1.27)
					(thickness 0.15)
				)
			)
		)
		(property "MPN" "CR0402-FX-2201GLF"
			(at 0 0 180)
			(unlocked yes)
			(layer "B.Fab")
			(hide yes)
			(effects
				(font
					(size 1 1)
					(thickness 0.15)
				)
				(justify mirror)
			)
		)
		(property "Manufacturer" "Bourns"
			(at 0 0 180)
			(unlocked yes)
			(layer "B.Fab")
			(hide yes)
			(effects
				(font
					(size 1 1)
					(thickness 0.15)
				)
				(justify mirror)
			)
		)
		(property "License" "Apache-2.0"
			(at 0 0 180)
			(unlocked yes)
			(layer "B.Fab")
			(hide yes)
			(effects
				(font
					(size 1 1)
					(thickness 0.15)
				)
				(justify mirror)
			)
		)
		(property "Author" "Antmicro"
			(at 0 0 180)
			(unlocked yes)
			(layer "B.Fab")
			(hide yes)
			(effects
				(font
					(size 1 1)
					(thickness 0.15)
				)
				(justify mirror)
			)
		)
		(property "Val" "2k2"
			(at 0 0 180)
			(unlocked yes)
			(layer "B.Fab")
			(hide yes)
			(effects
				(font
					(size 1 1)
					(thickness 0.15)
				)
				(justify mirror)
			)
		)
		(property "Tolerance" "1%"
			(at 0 0 180)
			(unlocked yes)
			(layer "B.Fab")
			(hide yes)
			(effects
				(font
					(size 1 1)
					(thickness 0.15)
				)
				(justify mirror)
			)
		)
		(sheetname "/Compute module/")
		(sheetfile "compute-module.kicad_sch")
		(attr smd)
		(fp_rect
			(start -0.925 0.47)
			(end 0.925 -0.47)
			(stroke
				(width 0.05)
				(type default)
			)
			(fill no)
			(layer "B.CrtYd")
		)
		(fp_rect
			(start -0.5 0.25)
			(end 0.5 -0.25)
			(stroke
				(width 0.15)
				(type solid)
			)
			(fill no)
			(layer "B.Fab")
		)
		(fp_text user "Author: Antmicro"
			(at -0.95 -4.169 0)
			(layer "B.Fab")
			(effects
				(font
					(size 0.7 0.7)
					(thickness 0.15)
				)
				(justify left bottom mirror)
			)
		)
		(fp_text user "${REFERENCE}"
			(at -0.95 -3.168 0)
			(layer "B.Fab")
			(effects
				(font
					(size 0.7 0.7)
					(thickness 0.15)
				)
				(justify left bottom mirror)
			)
		)
		(fp_text user "License: Apache-2.0"
			(at -0.95 -5.169 0)
			(layer "B.Fab")
			(effects
				(font
					(size 0.7 0.7)
					(thickness 0.15)
				)
				(justify left bottom mirror)
			)
		)
		(pad "1" smd roundrect
			(at -0.48 0 180)
			(size 0.59 0.64)
			(layers "B.Cu" "B.Mask" "B.Paste")
			(roundrect_rratio 0.25)
			(net 447 "/Compute module/GPIO.0{slash}SDA0")
			(pintype "passive")
		)
		(pad "2" smd roundrect
			(at 0.48 0 180)
			(size 0.59 0.64)
			(layers "B.Cu" "B.Mask" "B.Paste")
			(roundrect_rratio 0.25)
			(net 18 "V_{IO}")
			(pintype "passive")
		)
	)
)
